# BASEBOARD_FAB2 (Tioga Pass) — schematic netlist excerpt (pin names and nets, part order shuffled) for the footprints in the layout excerpt that follows; sources: Cadence DE-HDL packaged netlist, KiCad conversion of Wiwynn_Tioga_Pass_MB.brd

R1D27  RES  4.75K 1% EMPTY  pkg 0402  page 199 : A = A_HSC_VCAP ; B = FM_P12V_HSC_ADR2
C5A16  CAP_A  47UF 4V 20% X5R  pkg 0603V  page 220 : A = PVDDQ_DEF ; B = GND
C7A39  CAP_A  0.1UF 16V 10% X7R  pkg 0402V  page 236 : A = VR_FET_SW_P12V_STBY_PVDDQ_DEF ; B = GND

(kicad_pcb
	(version 20260206)
	(generator "pcbnew")
	(generator_version "10.0")
	(general
		(thickness 1.6)
		(legacy_teardrops no)
	)
	(paper "A4")
	(title_block
		(title "Wiwynn_Tioga_Pass_MB.brd")
		(comment 1 "Tioga Pass / footprints 19-21 of 4770")
	)
	(layers
		(0 "F.Cu" signal "TOP")
		(4 "In1.Cu" signal "L2GND")
		(6 "In2.Cu" signal "L3")
		(8 "In3.Cu" signal "L4GND")
		(10 "In4.Cu" signal "L5")
		(12 "In5.Cu" signal "L6GND")
		(14 "In6.Cu" signal "L7VCC")
		(16 "In7.Cu" signal "L8VCC")
		(18 "In8.Cu" signal "L9GND")
		(20 "In9.Cu" signal "L10")
		(22 "In10.Cu" signal "L11GND")
		(24 "In11.Cu" signal "L12")
		(26 "In12.Cu" signal "L13GND")
		(2 "B.Cu" signal "BOTTOM")
		(9 "F.Adhes" user "F.Adhesive")
		(11 "B.Adhes" user "B.Adhesive")
		(13 "F.Paste" user "Package Geometry/Pastemask Top")
		(15 "B.Paste" user "Package Geometry/Pastemask Bottom")
		(5 "F.SilkS" user "Ref Des/Silkscreen Top")
		(7 "B.SilkS" user "Ref Des/Silkscreen Bottom")
		(1 "F.Mask" user "Board Geometry/Soldermask Top")
		(3 "B.Mask" user "Board Geometry/Soldermask Bottom")
		(17 "Dwgs.User" user "User.Drawings")
		(19 "Cmts.User" user "User.Comments")
		(21 "Eco1.User" user "User.Eco1")
		(23 "Eco2.User" user "User.Eco2")
		(25 "Edge.Cuts" user "Board Geometry/Outline")
		(27 "Margin" user)
		(31 "F.CrtYd" user "Package Geometry/Place Bound Top")
		(29 "B.CrtYd" user "Package Geometry/Place Bound Bottom")
		(35 "F.Fab" user "Ref Des/Assembly Top")
		(33 "B.Fab" user "Ref Des/Assembly Bottom")
	)
	(footprint ""
		(layer "F.Cu")
		(at 380.538228 -154.247596)
		(property "Reference" "C7A39"
			(at 0 0 0)
			(layer "F.SilkS")
			(hide yes)
			(effects
				(font
					(size 1.27 1.27)
				)
			)
		)
		(property "Value" ""
			(at 0 0 0)
			(layer "F.Fab")
			(effects
				(font
					(size 1.27 1.27)
				)
			)
		)
		(duplicate_pad_numbers_are_jumpers no)
		(fp_poly
			(pts
				(xy 0.3048 -0.1016) (xy 0.3048 0.9906) (xy -0.3048 0.9906) (xy -0.3048 -0.1016)
			)
			(stroke
				(width 0)
				(type default)
			)
			(fill no)
			(layer "F.CrtYd")
		)
		(fp_line
			(start -0.3048 -0.1016)
			(end -0.3048 0.9906)
			(stroke
				(width 0.1)
				(type default)
			)
			(layer "F.Fab")
		)
		(fp_line
			(start -0.3048 0.9906)
			(end 0.3048 0.9906)
			(stroke
				(width 0.1)
				(type default)
			)
			(layer "F.Fab")
		)
		(fp_line
			(start 0.3048 -0.1016)
			(end -0.3048 -0.1016)
			(stroke
				(width 0.1)
				(type default)
			)
			(layer "F.Fab")
		)
		(fp_line
			(start 0.3048 0.9906)
			(end 0.3048 -0.1016)
			(stroke
				(width 0.1)
				(type default)
			)
			(layer "F.Fab")
		)
		(pad "1" smd rect
			(at 0 0)
			(size 0.508 0.508)
			(layers "F.Cu" "F.Mask" "F.Paste")
			(net "VR_FET_SW_P12V_STBY_PVDDQ_DEF")
		)
		(pad "2" smd rect
			(at 0 0.889)
			(size 0.508 0.508)
			(layers "F.Cu" "F.Mask" "F.Paste")
			(net "GND")
		)
		(zone
			(layer "F.Cu")
			(hatch none 0.5)
			(connect_pads
				(clearance 0)
			)
			(min_thickness 0.25)
			(keepout
				(tracks allowed)
				(vias not_allowed)
				(pads allowed)
				(copperpour not_allowed)
				(footprints allowed)
			)
			(placement
				(enabled no)
				(sheetname "")
			)
			(fill
				(thermal_gap 0.5)
				(thermal_bridge_width 0.5)
				(island_removal_mode 0)
			)
			(polygon
				(pts
					(xy 380.284228 -153.993596) (xy 380.792228 -153.993596) (xy 380.792228 -153.612596) (xy 380.284228 -153.612596)
				)
			)
		)
		(zone
			(layer "F.Cu")
			(hatch none 0.5)
			(connect_pads
				(clearance 0)
			)
			(min_thickness 0.25)
			(keepout
				(tracks not_allowed)
				(vias allowed)
				(pads allowed)
				(copperpour not_allowed)
				(footprints allowed)
			)
			(placement
				(enabled no)
				(sheetname "")
			)
			(fill
				(thermal_gap 0.5)
				(thermal_bridge_width 0.5)
				(island_removal_mode 0)
			)
			(polygon
				(pts
					(xy 380.284228 -153.612596) (xy 380.792228 -153.612596) (xy 380.792228 -153.993596) (xy 380.284228 -153.993596)
				)
			)
		)
	)
	(footprint ""
		(layer "F.Cu")
		(at 266.397232 -140.208 90)
		(property "Reference" "C5A16"
			(at 1.848866 0.752348 90)
			(unlocked yes)
			(layer "F.SilkS")
			(effects
				(font
					(size 1.27 0.9652)
					(thickness 0.1524)
				)
			)
		)
		(property "Value" ""
			(at 0 0 90)
			(layer "F.Fab")
			(effects
				(font
					(size 1.27 1.27)
				)
			)
		)
		(duplicate_pad_numbers_are_jumpers no)
		(fp_rect
			(start -0.500126 1.598422)
			(end 0.500126 -0.201422)
			(stroke
				(width 0)
				(type default)
			)
			(fill no)
			(layer "F.CrtYd")
		)
		(fp_line
			(start 0.500126 -0.201422)
			(end 0.500126 1.598422)
			(stroke
				(width 0.1)
				(type default)
			)
			(layer "F.Fab")
		)
		(fp_line
			(start -0.500126 -0.201422)
			(end 0.500126 -0.201422)
			(stroke
				(width 0.1)
				(type default)
			)
			(layer "F.Fab")
		)
		(fp_line
			(start 0.500126 1.598422)
			(end -0.500126 1.598422)
			(stroke
				(width 0.1)
				(type default)
			)
			(layer "F.Fab")
		)
		(fp_line
			(start -0.500126 1.598422)
			(end -0.500126 -0.201422)
			(stroke
				(width 0.1)
				(type default)
			)
			(layer "F.Fab")
		)
		(pad "1" smd rect
			(at 0 0)
			(size 0.889 0.9906)
			(layers "F.Cu" "F.Mask" "F.Paste")
			(net "PVDDQ_DEF")
		)
		(pad "2" smd rect
			(at 0 1.397)
			(size 0.889 0.9906)
			(layers "F.Cu" "F.Mask" "F.Paste")
			(net "GND")
		)
		(zone
			(layer "F.Cu")
			(hatch none 0.5)
			(connect_pads
				(clearance 0)
			)
			(min_thickness 0.25)
			(keepout
				(tracks allowed)
				(vias not_allowed)
				(pads allowed)
				(copperpour not_allowed)
				(footprints allowed)
			)
			(placement
				(enabled no)
				(sheetname "")
			)
			(fill
				(thermal_gap 0.5)
				(thermal_bridge_width 0.5)
				(island_removal_mode 0)
			)
			(polygon
				(pts
					(xy 267.349732 -139.7127) (xy 267.349732 -140.7033) (xy 266.841732 -140.7033) (xy 266.841732 -139.7127)
				)
			)
		)
		(zone
			(layer "F.Cu")
			(hatch none 0.5)
			(connect_pads
				(clearance 0)
			)
			(min_thickness 0.25)
			(keepout
				(tracks not_allowed)
				(vias allowed)
				(pads allowed)
				(copperpour not_allowed)
				(footprints allowed)
			)
			(placement
				(enabled no)
				(sheetname "")
			)
			(fill
				(thermal_gap 0.5)
				(thermal_bridge_width 0.5)
				(island_removal_mode 0)
			)
			(polygon
				(pts
					(xy 267.349732 -139.7127) (xy 267.349732 -140.7033) (xy 266.841732 -140.7033) (xy 266.841732 -139.7127)
				)
			)
		)
	)
	(footprint ""
		(layer "F.Cu")
		(at 23.114 -79.629 -90)
		(property "Reference" "R1D27"
			(at 0 0 270)
			(layer "F.SilkS")
			(hide yes)
			(effects
				(font
					(size 1.27 1.27)
				)
			)
		)
		(property "Value" ""
			(at 0 0 270)
			(layer "F.Fab")
			(effects
				(font
					(size 1.27 1.27)
				)
			)
		)
		(duplicate_pad_numbers_are_jumpers no)
		(fp_rect
			(start -0.2794 -0.1016)
			(end 0.2794 0.9906)
			(stroke
				(width 0)
				(type default)
			)
			(fill no)
			(layer "F.CrtYd")
		)
		(fp_line
			(start -0.2794 0.9906)
			(end 0.2794 0.9906)
			(stroke
				(width 0.1)
				(type default)
			)
			(layer "F.Fab")
		)
		(fp_line
			(start 0.2794 0.9906)
			(end 0.2794 -0.1016)
			(stroke
				(width 0.1)
				(type default)
			)
			(layer "F.Fab")
		)
		(fp_line
			(start -0.2794 -0.1016)
			(end -0.2794 0.9906)
			(stroke
				(width 0.1)
				(type default)
			)
			(layer "F.Fab")
		)
		(fp_line
			(start 0.2794 -0.1016)
			(end -0.2794 -0.1016)
			(stroke
				(width 0.1)
				(type default)
			)
			(layer "F.Fab")
		)
		(pad "1" smd rect
			(at 0 0 270)
			(size 0.508 0.508)
			(layers "F.Cu" "F.Mask" "F.Paste")
			(net "A_HSC_VCAP")
		)
		(pad "2" smd rect
			(at 0 0.889 270)
			(size 0.508 0.508)
			(layers "F.Cu" "F.Mask" "F.Paste")
			(net "FM_P12V_HSC_ADR2")
		)
		(zone
			(layer "F.Cu")
			(hatch none 0.5)
			(connect_pads
				(clearance 0)
			)
			(min_thickness 0.25)
			(keepout
				(tracks not_allowed)
				(vias allowed)
				(pads allowed)
				(copperpour not_allowed)
				(footprints allowed)
			)
			(placement
				(enabled no)
				(sheetname "")
			)
			(fill
				(thermal_gap 0.5)
				(thermal_bridge_width 0.5)
				(island_removal_mode 0)
			)
			(polygon
				(pts
					(xy 22.86 -79.883) (xy 22.479 -79.883) (xy 22.479 -79.375) (xy 22.86 -79.375)
				)
			)
		)
		(zone
			(layer "F.Cu")
			(hatch none 0.5)
			(connect_pads
				(clearance 0)
			)
			(min_thickness 0.25)
			(keepout
				(tracks allowed)
				(vias not_allowed)
				(pads allowed)
				(copperpour not_allowed)
				(footprints allowed)
			)
			(placement
				(enabled no)
				(sheetname "")
			)
			(fill
				(thermal_gap 0.5)
				(thermal_bridge_width 0.5)
				(island_removal_mode 0)
			)
			(polygon
				(pts
					(xy 22.86 -79.883) (xy 22.479 -79.883) (xy 22.479 -79.375) (xy 22.86 -79.375)
				)
			)
		)
	)
)
